(kicad_pcb
	(version 20260206)
	(generator "pcbnew")
	(generator_version "10.0")
	(general
		(thickness 1.6)
		(legacy_teardrops no)
	)
	(paper "A4")
	(title_block
		(title "Bryce Canyon_F.DPB_16315-1-OCP.brd")
		(comment 1 "Bryce Canyon / footprints 1440-1447 of 2223")
	)
	(layers
		(0 "F.Cu" signal "TOP")
		(4 "In1.Cu" signal "L2GND")
		(6 "In2.Cu" signal "L3")
		(8 "In3.Cu" signal "L4GND")
		(10 "In4.Cu" signal "L5")
		(12 "In5.Cu" signal "L6VCC")
		(14 "In6.Cu" signal "L7VCC")
		(16 "In7.Cu" signal "L8")
		(18 "In8.Cu" signal "L9GND")
		(20 "In9.Cu" signal "L10")
		(22 "In10.Cu" signal "L11GND")
		(2 "B.Cu" signal "BOTTOM")
		(9 "F.Adhes" user "F.Adhesive")
		(11 "B.Adhes" user "B.Adhesive")
		(13 "F.Paste" user "Package Geometry/Pastemask Top")
		(15 "B.Paste" user "Package Geometry/Pastemask Bottom")
		(5 "F.SilkS" user "Ref Des/Silkscreen Top")
		(7 "B.SilkS" user "Ref Des/Silkscreen Bottom")
		(1 "F.Mask" user "Board Geometry/Soldermask Top")
		(3 "B.Mask" user "Board Geometry/Soldermask Bottom")
		(17 "Dwgs.User" user "User.Drawings")
		(19 "Cmts.User" user "User.Comments")
		(21 "Eco1.User" user "User.Eco1")
		(23 "Eco2.User" user "User.Eco2")
		(25 "Edge.Cuts" user "Board Geometry/Outline")
		(27 "Margin" user)
		(31 "F.CrtYd" user "Package Geometry/Place Bound Top")
		(29 "B.CrtYd" user "Package Geometry/Place Bound Bottom")
		(35 "F.Fab" user "Ref Des/Assembly Top")
		(33 "B.Fab" user "Ref Des/Assembly Bottom")
	)
	(footprint ""
		(layer "F.Cu")
		(at 457.6699 -176.127918 -90)
		(property "Reference" "R635"
			(at 0 0 270)
			(layer "F.SilkS")
			(hide yes)
			(effects
				(font
					(size 1.27 1.27)
				)
			)
		)
		(property "Value" "2R6F-GP"
			(at -0.0508 -4.8514 270)
			(unlocked yes)
			(layer "F.Fab")
			(hide yes)
			(effects
				(font
					(size 1.016 1.016)
					(thickness 0.1524)
				)
			)
		)
		(property "Device Type" "R1206H26"
			(at 0 -6.3754 270)
			(unlocked yes)
			(layer "F.Fab")
			(hide yes)
			(effects
				(font
					(size 1.016 1.016)
					(thickness 0.1524)
				)
			)
		)
		(duplicate_pad_numbers_are_jumpers no)
		(fp_line
			(start -1.016 2.2352)
			(end -1.016 -2.2352)
			(stroke
				(width 0.1524)
				(type default)
			)
			(layer "F.SilkS")
		)
		(fp_line
			(start 1.016 2.2352)
			(end -1.016 2.2352)
			(stroke
				(width 0.1524)
				(type default)
			)
			(layer "F.SilkS")
		)
		(fp_line
			(start -1.016 -2.2352)
			(end 1.016 -2.2352)
			(stroke
				(width 0.1524)
				(type default)
			)
			(layer "F.SilkS")
		)
		(fp_line
			(start 1.016 -2.2352)
			(end 1.016 2.2352)
			(stroke
				(width 0.1524)
				(type default)
			)
			(layer "F.SilkS")
		)
		(fp_rect
			(start -1.0922 2.3114)
			(end 1.0922 -2.3114)
			(stroke
				(width 0)
				(type default)
			)
			(fill no)
			(layer "F.CrtYd")
		)
		(fp_poly
			(pts
				(xy -1.0922 -2.3114) (xy 1.0922 -2.3114) (xy 1.0922 2.3114) (xy -1.0922 2.3114)
			)
			(stroke
				(width 0)
				(type default)
			)
			(fill no)
			(layer "F.Fab")
		)
		(pad "1" smd rect
			(at 0 -1.397 270)
			(size 1.651 1.27)
			(layers "F.Cu" "F.Mask" "F.Paste")
			(net "P5V_HDD22")
		)
		(pad "2" smd rect
			(at 0 1.397 270)
			(size 1.651 1.27)
			(layers "F.Cu" "F.Mask" "F.Paste")
			(net "5V_PRE_22")
		)
	)
	(footprint ""
		(layer "F.Cu")
		(at 243.9416 -260.5532)
		(property "Reference" "R48"
			(at 0 0 0)
			(layer "F.SilkS")
			(hide yes)
			(effects
				(font
					(size 1.27 1.27)
				)
			)
		)
		(property "Value" "4K7R2F-GP"
			(at 0.064008 -3.993896 0)
			(unlocked yes)
			(layer "F.Fab")
			(hide yes)
			(effects
				(font
					(size 1.016 1.016)
					(thickness 0.1524)
				)
			)
		)
		(property "Device Type" "R402H16"
			(at 0.064008 -5.517896 0)
			(unlocked yes)
			(layer "F.Fab")
			(hide yes)
			(effects
				(font
					(size 1.016 1.016)
					(thickness 0.1524)
				)
			)
		)
		(duplicate_pad_numbers_are_jumpers no)
		(fp_line
			(start -0.508 -0.9398)
			(end -0.508 0.9398)
			(stroke
				(width 0.1524)
				(type default)
			)
			(layer "F.SilkS")
		)
		(fp_line
			(start 0.508 -0.9398)
			(end -0.508 -0.9398)
			(stroke
				(width 0.1524)
				(type default)
			)
			(layer "F.SilkS")
		)
		(fp_rect
			(start -0.508 0.9398)
			(end 0.508 -0.9398)
			(stroke
				(width 0)
				(type default)
			)
			(fill no)
			(layer "F.CrtYd")
		)
		(fp_rect
			(start -0.508 0.9398)
			(end 0.508 -0.9398)
			(stroke
				(width 0)
				(type default)
			)
			(fill no)
			(layer "F.Fab")
		)
		(pad "1" smd custom
			(at 0 -0.4445)
			(size 0.1397 0.1397)
			(layers "F.Cu" "F.Mask" "F.Paste")
			(net "P3V3_STBY_A")
			(options
				(clearance outline)
				(anchor circle)
			)
			(primitives
				(gr_poly
					(pts
						(arc
							(start -0.1778 -0.2794)
							(mid -0.249642 -0.249642)
							(end -0.2794 -0.1778)
						)
						(arc
							(start -0.2794 0.1778)
							(mid -0.249642 0.249642)
							(end -0.1778 0.2794)
						)
						(arc
							(start 0.1778 0.2794)
							(mid 0.249642 0.249642)
							(end 0.2794 0.1778)
						)
						(arc
							(start 0.2794 -0.1778)
							(mid 0.249642 -0.249642)
							(end 0.1778 -0.2794)
						)
					)
					(width 0)
					(fill yes)
				)
			)
		)
		(pad "2" smd custom
			(at 0 0.4445)
			(size 0.1397 0.1397)
			(layers "F.Cu" "F.Mask" "F.Paste")
			(net "IO_EXP5_A0")
			(options
				(clearance outline)
				(anchor circle)
			)
			(primitives
				(gr_poly
					(pts
						(arc
							(start -0.1778 -0.2794)
							(mid -0.249642 -0.249642)
							(end -0.2794 -0.1778)
						)
						(arc
							(start -0.2794 0.1778)
							(mid -0.249642 0.249642)
							(end -0.1778 0.2794)
						)
						(arc
							(start 0.1778 0.2794)
							(mid 0.249642 0.249642)
							(end 0.2794 0.1778)
						)
						(arc
							(start 0.2794 -0.1778)
							(mid 0.249642 -0.249642)
							(end 0.1778 -0.2794)
						)
					)
					(width 0)
					(fill yes)
				)
			)
		)
	)
	(footprint ""
		(layer "F.Cu")
		(at 176.2506 -45.633894)
		(property "Reference" "R814"
			(at 0 0 0)
			(layer "F.SilkS")
			(hide yes)
			(effects
				(font
					(size 1.27 1.27)
				)
			)
		)
		(property "Value" "0R2J-2-GP"
			(at 0.064008 -3.993896 0)
			(unlocked yes)
			(layer "F.Fab")
			(hide yes)
			(effects
				(font
					(size 1.016 1.016)
					(thickness 0.1524)
				)
			)
		)
		(property "Device Type" "R402H16"
			(at 0.064008 -5.517896 0)
			(unlocked yes)
			(layer "F.Fab")
			(hide yes)
			(effects
				(font
					(size 1.016 1.016)
					(thickness 0.1524)
				)
			)
		)
		(duplicate_pad_numbers_are_jumpers no)
		(fp_line
			(start -0.508 -0.9398)
			(end -0.508 0.9398)
			(stroke
				(width 0.1524)
				(type default)
			)
			(layer "F.SilkS")
		)
		(fp_line
			(start 0.508 -0.9398)
			(end -0.508 -0.9398)
			(stroke
				(width 0.1524)
				(type default)
			)
			(layer "F.SilkS")
		)
		(fp_rect
			(start -0.508 0.9398)
			(end 0.508 -0.9398)
			(stroke
				(width 0)
				(type default)
			)
			(fill no)
			(layer "F.CrtYd")
		)
		(fp_rect
			(start -0.508 0.9398)
			(end 0.508 -0.9398)
			(stroke
				(width 0)
				(type default)
			)
			(fill no)
			(layer "F.Fab")
		)
		(pad "1" smd custom
			(at 0 -0.4445)
			(size 0.1397 0.1397)
			(layers "F.Cu" "F.Mask" "F.Paste")
			(net "SW_HDD_G29")
			(options
				(clearance outline)
				(anchor circle)
			)
			(primitives
				(gr_poly
					(pts
						(arc
							(start -0.1778 -0.2794)
							(mid -0.249642 -0.249642)
							(end -0.2794 -0.1778)
						)
						(arc
							(start -0.2794 0.1778)
							(mid -0.249642 0.249642)
							(end -0.1778 0.2794)
						)
						(arc
							(start 0.1778 0.2794)
							(mid 0.249642 0.249642)
							(end 0.2794 0.1778)
						)
						(arc
							(start 0.2794 -0.1778)
							(mid 0.249642 -0.249642)
							(end 0.1778 -0.2794)
						)
					)
					(width 0)
					(fill yes)
				)
			)
		)
		(pad "2" smd custom
			(at 0 0.4445)
			(size 0.1397 0.1397)
			(layers "F.Cu" "F.Mask" "F.Paste")
			(net "SW_HDD_R29")
			(options
				(clearance outline)
				(anchor circle)
			)
			(primitives
				(gr_poly
					(pts
						(arc
							(start -0.1778 -0.2794)
							(mid -0.249642 -0.249642)
							(end -0.2794 -0.1778)
						)
						(arc
							(start -0.2794 0.1778)
							(mid -0.249642 0.249642)
							(end -0.1778 0.2794)
						)
						(arc
							(start 0.1778 0.2794)
							(mid 0.249642 0.249642)
							(end 0.2794 0.1778)
						)
						(arc
							(start 0.2794 -0.1778)
							(mid 0.249642 -0.249642)
							(end 0.1778 -0.2794)
						)
					)
					(width 0)
					(fill yes)
				)
			)
		)
	)
	(footprint ""
		(layer "F.Cu")
		(at 162.657536 -130.185414 -90)
		(property "Reference" "R524"
			(at 0 0 270)
			(layer "F.SilkS")
			(hide yes)
			(effects
				(font
					(size 1.27 1.27)
				)
			)
		)
		(property "Value" "4K7R2J-2-GP"
			(at 0.064008 -3.993896 270)
			(unlocked yes)
			(layer "F.Fab")
			(hide yes)
			(effects
				(font
					(size 1.016 1.016)
					(thickness 0.1524)
				)
			)
		)
		(property "Device Type" "R402H16"
			(at 0.064008 -5.517896 270)
			(unlocked yes)
			(layer "F.Fab")
			(hide yes)
			(effects
				(font
					(size 1.016 1.016)
					(thickness 0.1524)
				)
			)
		)
		(duplicate_pad_numbers_are_jumpers no)
		(fp_line
			(start -0.508 -0.9398)
			(end -0.508 0.9398)
			(stroke
				(width 0.1524)
				(type default)
			)
			(layer "F.SilkS")
		)
		(fp_line
			(start 0.508 -0.9398)
			(end -0.508 -0.9398)
			(stroke
				(width 0.1524)
				(type default)
			)
			(layer "F.SilkS")
		)
		(fp_rect
			(start -0.508 0.9398)
			(end 0.508 -0.9398)
			(stroke
				(width 0)
				(type default)
			)
			(fill no)
			(layer "F.CrtYd")
		)
		(fp_rect
			(start -0.508 0.9398)
			(end 0.508 -0.9398)
			(stroke
				(width 0)
				(type default)
			)
			(fill no)
			(layer "F.Fab")
		)
		(pad "1" smd custom
			(at 0 -0.4445 270)
			(size 0.1397 0.1397)
			(layers "F.Cu" "F.Mask" "F.Paste")
			(net "DRIVE_A_17_FLT_LED")
			(options
				(clearance outline)
				(anchor circle)
			)
			(primitives
				(gr_poly
					(pts
						(arc
							(start -0.1778 -0.2794)
							(mid -0.249642 -0.249642)
							(end -0.2794 -0.1778)
						)
						(arc
							(start -0.2794 0.1778)
							(mid -0.249642 0.249642)
							(end -0.1778 0.2794)
						)
						(arc
							(start 0.1778 0.2794)
							(mid 0.249642 0.249642)
							(end 0.2794 0.1778)
						)
						(arc
							(start 0.2794 -0.1778)
							(mid 0.249642 -0.249642)
							(end 0.1778 -0.2794)
						)
					)
					(width 0)
					(fill yes)
				)
			)
		)
		(pad "2" smd custom
			(at 0 0.4445 270)
			(size 0.1397 0.1397)
			(layers "F.Cu" "F.Mask" "F.Paste")
			(net "GND")
			(options
				(clearance outline)
				(anchor circle)
			)
			(primitives
				(gr_poly
					(pts
						(arc
							(start -0.1778 -0.2794)
							(mid -0.249642 -0.249642)
							(end -0.2794 -0.1778)
						)
						(arc
							(start -0.2794 0.1778)
							(mid -0.249642 0.249642)
							(end -0.1778 0.2794)
						)
						(arc
							(start 0.1778 0.2794)
							(mid 0.249642 0.249642)
							(end 0.2794 0.1778)
						)
						(arc
							(start 0.2794 -0.1778)
							(mid 0.249642 -0.249642)
							(end 0.1778 -0.2794)
						)
					)
					(width 0)
					(fill yes)
				)
			)
		)
	)
	(footprint ""
		(layer "F.Cu")
		(at 172.4406 -277.6474 90)
		(property "Reference" "R259"
			(at 0 0 90)
			(layer "F.SilkS")
			(hide yes)
			(effects
				(font
					(size 1.27 1.27)
				)
			)
		)
		(property "Value" "4K7R2J-2-GP"
			(at 0.064008 -3.993896 90)
			(unlocked yes)
			(layer "F.Fab")
			(hide yes)
			(effects
				(font
					(size 1.016 1.016)
					(thickness 0.1524)
				)
			)
		)
		(property "Device Type" "R402H16"
			(at 0.064008 -5.517896 90)
			(unlocked yes)
			(layer "F.Fab")
			(hide yes)
			(effects
				(font
					(size 1.016 1.016)
					(thickness 0.1524)
				)
			)
		)
		(duplicate_pad_numbers_are_jumpers no)
		(fp_line
			(start 0.508 -0.9398)
			(end -0.508 -0.9398)
			(stroke
				(width 0.1524)
				(type default)
			)
			(layer "F.SilkS")
		)
		(fp_line
			(start -0.508 -0.9398)
			(end -0.508 0.9398)
			(stroke
				(width 0.1524)
				(type default)
			)
			(layer "F.SilkS")
		)
		(fp_rect
			(start -0.508 0.9398)
			(end 0.508 -0.9398)
			(stroke
				(width 0)
				(type default)
			)
			(fill no)
			(layer "F.CrtYd")
		)
		(fp_rect
			(start -0.508 0.9398)
			(end 0.508 -0.9398)
			(stroke
				(width 0)
				(type default)
			)
			(fill no)
			(layer "F.Fab")
		)
		(pad "1" smd custom
			(at 0 -0.4445 90)
			(size 0.1397 0.1397)
			(layers "F.Cu" "F.Mask" "F.Paste")
			(net "P12V_A")
			(options
				(clearance outline)
				(anchor circle)
			)
			(primitives
				(gr_poly
					(pts
						(arc
							(start -0.1778 -0.2794)
							(mid -0.249642 -0.249642)
							(end -0.2794 -0.1778)
						)
						(arc
							(start -0.2794 0.1778)
							(mid -0.249642 0.249642)
							(end -0.1778 0.2794)
						)
						(arc
							(start 0.1778 0.2794)
							(mid 0.249642 0.249642)
							(end 0.2794 0.1778)
						)
						(arc
							(start 0.2794 -0.1778)
							(mid 0.249642 -0.249642)
							(end 0.1778 -0.2794)
						)
					)
					(width 0)
					(fill yes)
				)
			)
		)
		(pad "2" smd custom
			(at 0 0.4445 90)
			(size 0.1397 0.1397)
			(layers "F.Cu" "F.Mask" "F.Paste")
			(net "SW_HDD_R5")
			(options
				(clearance outline)
				(anchor circle)
			)
			(primitives
				(gr_poly
					(pts
						(arc
							(start -0.1778 -0.2794)
							(mid -0.249642 -0.249642)
							(end -0.2794 -0.1778)
						)
						(arc
							(start -0.2794 0.1778)
							(mid -0.249642 0.249642)
							(end -0.1778 0.2794)
						)
						(arc
							(start 0.1778 0.2794)
							(mid 0.249642 0.249642)
							(end 0.2794 0.1778)
						)
						(arc
							(start 0.2794 -0.1778)
							(mid 0.249642 -0.249642)
							(end 0.1778 -0.2794)
						)
					)
					(width 0)
					(fill yes)
				)
			)
		)
	)
	(footprint ""
		(layer "F.Cu")
		(at 16.824198 -167.110918 90)
		(property "Reference" "R413"
			(at 0 0 90)
			(layer "F.SilkS")
			(hide yes)
			(effects
				(font
					(size 1.27 1.27)
				)
			)
		)
		(property "Value" "4K7R2J-2-GP"
			(at 0.064008 -3.993896 90)
			(unlocked yes)
			(layer "F.Fab")
			(hide yes)
			(effects
				(font
					(size 1.016 1.016)
					(thickness 0.1524)
				)
			)
		)
		(property "Device Type" "R402H16"
			(at 0.064008 -5.517896 90)
			(unlocked yes)
			(layer "F.Fab")
			(hide yes)
			(effects
				(font
					(size 1.016 1.016)
					(thickness 0.1524)
				)
			)
		)
		(duplicate_pad_numbers_are_jumpers no)
		(fp_line
			(start 0.508 -0.9398)
			(end -0.508 -0.9398)
			(stroke
				(width 0.1524)
				(type default)
			)
			(layer "F.SilkS")
		)
		(fp_line
			(start -0.508 -0.9398)
			(end -0.508 0.9398)
			(stroke
				(width 0.1524)
				(type default)
			)
			(layer "F.SilkS")
		)
		(fp_rect
			(start -0.508 0.9398)
			(end 0.508 -0.9398)
			(stroke
				(width 0)
				(type default)
			)
			(fill no)
			(layer "F.CrtYd")
		)
		(fp_rect
			(start -0.508 0.9398)
			(end 0.508 -0.9398)
			(stroke
				(width 0)
				(type default)
			)
			(fill no)
			(layer "F.Fab")
		)
		(pad "1" smd custom
			(at 0 -0.4445 90)
			(size 0.1397 0.1397)
			(layers "F.Cu" "F.Mask" "F.Paste")
			(net "P12V_A")
			(options
				(clearance outline)
				(anchor circle)
			)
			(primitives
				(gr_poly
					(pts
						(arc
							(start -0.1778 -0.2794)
							(mid -0.249642 -0.249642)
							(end -0.2794 -0.1778)
						)
						(arc
							(start -0.2794 0.1778)
							(mid -0.249642 0.249642)
							(end -0.1778 0.2794)
						)
						(arc
							(start 0.1778 0.2794)
							(mid 0.249642 0.249642)
							(end 0.2794 0.1778)
						)
						(arc
							(start 0.2794 -0.1778)
							(mid 0.249642 -0.249642)
							(end 0.1778 -0.2794)
						)
					)
					(width 0)
					(fill yes)
				)
			)
		)
		(pad "2" smd custom
			(at 0 0.4445 90)
			(size 0.1397 0.1397)
			(layers "F.Cu" "F.Mask" "F.Paste")
			(net "SW_HDD_P12")
			(options
				(clearance outline)
				(anchor circle)
			)
			(primitives
				(gr_poly
					(pts
						(arc
							(start -0.1778 -0.2794)
							(mid -0.249642 -0.249642)
							(end -0.2794 -0.1778)
						)
						(arc
							(start -0.2794 0.1778)
							(mid -0.249642 0.249642)
							(end -0.1778 0.2794)
						)
						(arc
							(start 0.1778 0.2794)
							(mid 0.249642 0.249642)
							(end 0.2794 0.1778)
						)
						(arc
							(start 0.2794 -0.1778)
							(mid 0.249642 -0.249642)
							(end 0.1778 -0.2794)
						)
					)
					(width 0)
					(fill yes)
				)
			)
		)
	)
	(footprint ""
		(layer "F.Cu")
		(at 20.049998 -61.000894 -90)
		(property "Reference" "C353"
			(at 0 0 270)
			(layer "F.SilkS")
			(hide yes)
			(effects
				(font
					(size 1.27 1.27)
				)
			)
		)
		(property "Value" "SC10U16V6KX-2GP"
			(at -0.0762 -5.1308 270)
			(unlocked yes)
			(layer "F.Fab")
			(hide yes)
			(effects
				(font
					(size 1.016 1.016)
					(thickness 0.1524)
				)
			)
		)
		(property "Device Type" "C1206H71"
			(at -0.127 -6.6548 270)
			(unlocked yes)
			(layer "F.Fab")
			(hide yes)
			(effects
				(font
					(size 1.016 1.016)
					(thickness 0.1524)
				)
			)
		)
		(duplicate_pad_numbers_are_jumpers no)
		(fp_line
			(start -1.016 2.2352)
			(end -1.016 0.8382)
			(stroke
				(width 0.1524)
				(type default)
			)
			(layer "F.SilkS")
		)
		(fp_line
			(start 1.016 2.2352)
			(end -1.016 2.2352)
			(stroke
				(width 0.1524)
				(type default)
			)
			(layer "F.SilkS")
		)
		(fp_line
			(start 1.016 0.8382)
			(end 1.016 2.2352)
			(stroke
				(width 0.1524)
				(type default)
			)
			(layer "F.SilkS")
		)
		(fp_line
			(start -1.016 -0.8382)
			(end -1.016 -2.2352)
			(stroke
				(width 0.1524)
				(type default)
			)
			(layer "F.SilkS")
		)
		(fp_line
			(start -1.016 -2.2352)
			(end 1.016 -2.2352)
			(stroke
				(width 0.1524)
				(type default)
			)
			(layer "F.SilkS")
		)
		(fp_line
			(start 1.016 -2.2352)
			(end 1.016 -0.8382)
			(stroke
				(width 0.1524)
				(type default)
			)
			(layer "F.SilkS")
		)
		(fp_rect
			(start -1.0922 2.3114)
			(end 1.0922 -2.3114)
			(stroke
				(width 0)
				(type default)
			)
			(fill no)
			(layer "F.CrtYd")
		)
		(fp_poly
			(pts
				(xy 1.0922 -2.3114) (xy 1.0922 2.3114) (xy -1.0922 2.3114) (xy -1.0922 -2.3114)
			)
			(stroke
				(width 0)
				(type default)
			)
			(fill no)
			(layer "F.Fab")
		)
		(pad "1" smd rect
			(at 0 -1.397 270)
			(size 1.651 1.27)
			(layers "F.Cu" "F.Mask" "F.Paste")
			(net "P5V_HDD24")
		)
		(pad "2" smd rect
			(at 0 1.397 270)
			(size 1.651 1.27)
			(layers "F.Cu" "F.Mask" "F.Paste")
			(net "GND")
		)
	)
	(footprint ""
		(layer "F.Cu")
		(at 272.542 -312.704988 180)
		(property "Reference" "VIA67"
			(at 0 0 180)
			(layer "F.SilkS")
			(hide yes)
			(effects
				(font
					(size 1.27 1.27)
				)
			)
		)
		(property "Value" "100OHM-8L-1D6MM-L18L16-GP"
			(at -3.7211 -4.5085 180)
			(unlocked yes)
			(layer "F.Fab")
			(hide yes)
			(effects
				(font
					(size 1.016 1.016)
					(thickness 0.1524)
				)
			)
		)
		(property "Device Type" "VIA-PCIE-4P-394076"
			(at -3.7211 -6.0325 180)
			(unlocked yes)
			(layer "F.Fab")
			(hide yes)
			(effects
				(font
					(size 1.016 1.016)
					(thickness 0.1524)
				)
			)
		)
		(duplicate_pad_numbers_are_jumpers no)
		(fp_rect
			(start -1.9685 0.381)
			(end 1.9685 -0.381)
			(stroke
				(width 0)
				(type default)
			)
			(fill no)
			(layer "F.CrtYd")
		)
		(fp_rect
			(start -1.9685 0.381)
			(end 1.9685 -0.381)
			(stroke
				(width 0)
				(type default)
			)
			(fill no)
			(layer "F.Fab")
		)
		(pad "1" thru_hole circle
			(at -1.5875 0 180)
			(size 0.508 0.508)
			(drill 0.254)
			(layers "*.Cu" "*.Mask")
			(remove_unused_layers no)
			(net "GND")
			(clearance 0.127)
			(thermal_gap 0.127)
		)
		(pad "2" thru_hole circle
			(at -0.5715 0 180)
			(size 0.508 0.508)
			(drill 0.254)
			(layers "*.Cu" "*.Mask")
			(remove_unused_layers no)
			(net "PHY_SCC_A_TO_DRV_A_26_DP")
			(clearance 0.127)
			(thermal_gap 0.127)
		)
		(pad "3" thru_hole circle
			(at 0.5715 0 180)
			(size 0.508 0.508)
			(drill 0.254)
			(layers "*.Cu" "*.Mask")
			(remove_unused_layers no)
			(net "PHY_SCC_A_TO_DRV_A_26_DN")
			(clearance 0.127)
			(thermal_gap 0.127)
		)
		(pad "4" thru_hole circle
			(at 1.5875 0 180)
			(size 0.508 0.508)
			(drill 0.254)
			(layers "*.Cu" "*.Mask")
			(remove_unused_layers no)
			(net "GND")
			(clearance 0.127)
			(thermal_gap 0.127)
		)
	)
)
